(kicad_pcb
	(version 20260206)
	(generator "pcbnew")
	(generator_version "10.0")
	(general
		(thickness 1.6)
		(legacy_teardrops no)
	)
	(paper "A4")
	(title_block
		(title "Bryce Canyon_R.DPB_16317-1_OCP.brd")
		(comment 1 "Bryce Canyon / footprints 275-282 of 2099")
	)
	(layers
		(0 "F.Cu" signal "TOP")
		(4 "In1.Cu" signal "L2GND")
		(6 "In2.Cu" signal "L3")
		(8 "In3.Cu" signal "L4VCC")
		(10 "In4.Cu" signal "L5VCC")
		(12 "In5.Cu" signal "L6")
		(14 "In6.Cu" signal "L7GND")
		(2 "B.Cu" signal "BOTTOM")
		(9 "F.Adhes" user "F.Adhesive")
		(11 "B.Adhes" user "B.Adhesive")
		(13 "F.Paste" user "Package Geometry/Pastemask Top")
		(15 "B.Paste" user "Package Geometry/Pastemask Bottom")
		(5 "F.SilkS" user "Ref Des/Silkscreen Top")
		(7 "B.SilkS" user "Ref Des/Silkscreen Bottom")
		(1 "F.Mask" user "Board Geometry/Soldermask Top")
		(3 "B.Mask" user "Board Geometry/Soldermask Bottom")
		(17 "Dwgs.User" user "User.Drawings")
		(19 "Cmts.User" user "User.Comments")
		(21 "Eco1.User" user "User.Eco1")
		(23 "Eco2.User" user "User.Eco2")
		(25 "Edge.Cuts" user "Board Geometry/Outline")
		(27 "Margin" user)
		(31 "F.CrtYd" user "Package Geometry/Place Bound Top")
		(29 "B.CrtYd" user "Package Geometry/Place Bound Bottom")
		(35 "F.Fab" user "Ref Des/Assembly Top")
		(33 "B.Fab" user "Ref Des/Assembly Bottom")
	)
	(footprint ""
		(layer "F.Cu")
		(at 37.9222 -9.4742 -90)
		(property "Reference" "TP2"
			(at 0 0 270)
			(layer "F.SilkS")
			(hide yes)
			(effects
				(font
					(size 1.27 1.27)
				)
			)
		)
		(property "Value" "*"
			(at -0.0508 -1.6764 270)
			(unlocked yes)
			(layer "F.Fab")
			(hide yes)
			(effects
				(font
					(size 1.016 1.016)
					(thickness 0.1524)
				)
			)
		)
		(property "Device Type" "TPAD32"
			(at -0.0508 -3.2004 270)
			(unlocked yes)
			(layer "F.Fab")
			(hide yes)
			(effects
				(font
					(size 1.016 1.016)
					(thickness 0.1524)
				)
			)
		)
		(duplicate_pad_numbers_are_jumpers no)
		(fp_poly
			(pts
				(arc
					(start 0 -0.4064)
					(mid 0 0.4064)
					(end 0 -0.4064)
				)
			)
			(stroke
				(width 0)
				(type default)
			)
			(fill no)
			(layer "F.CrtYd")
		)
		(fp_poly
			(pts
				(arc
					(start 0 -0.7112)
					(mid 0 0.7112)
					(end 0 -0.7112)
				)
			)
			(stroke
				(width 0)
				(type default)
			)
			(fill no)
			(layer "F.Fab")
		)
		(pad "1" smd circle
			(at 0 0 270)
			(size 0.8128 0.8128)
			(layers "F.Cu" "F.Mask" "F.Paste")
			(net "TEMP1_ALERT")
		)
	)
	(footprint ""
		(layer "F.Cu")
		(at 477.536002 -13.6271 180)
		(property "Reference" "VIA71"
			(at 0 0 180)
			(layer "F.SilkS")
			(hide yes)
			(effects
				(font
					(size 1.27 1.27)
				)
			)
		)
		(property "Value" "100OHM-8L-2D36MM-L18-GP"
			(at 3.8989 0.5715 180)
			(unlocked yes)
			(layer "F.Fab")
			(hide yes)
			(effects
				(font
					(size 1.016 1.016)
					(thickness 0.1524)
				)
			)
		)
		(property "Device Type" "VIA-PCIE-4P-414097"
			(at 3.8989 -0.9525 180)
			(unlocked yes)
			(layer "F.Fab")
			(hide yes)
			(effects
				(font
					(size 1.016 1.016)
					(thickness 0.1524)
				)
			)
		)
		(duplicate_pad_numbers_are_jumpers no)
		(fp_rect
			(start -2.0701 0.4826)
			(end 2.0701 -0.4826)
			(stroke
				(width 0)
				(type default)
			)
			(fill no)
			(layer "F.CrtYd")
		)
		(fp_rect
			(start -2.0701 0.4826)
			(end 2.0701 -0.4826)
			(stroke
				(width 0)
				(type default)
			)
			(fill no)
			(layer "F.Fab")
		)
		(pad "1" thru_hole circle
			(at -1.5875 0 180)
			(size 0.508 0.508)
			(drill 0.254)
			(layers "*.Cu" "*.Mask")
			(remove_unused_layers no)
			(net "GND")
			(clearance 0.2286)
			(thermal_gap 0.2286)
		)
		(pad "2" thru_hole circle
			(at -0.5715 0 180)
			(size 0.508 0.508)
			(drill 0.254)
			(layers "*.Cu" "*.Mask")
			(remove_unused_layers no)
			(net "PHY_SCC_B_TO_DRV_B_35_DP")
			(clearance 0.2286)
			(thermal_gap 0.2286)
		)
		(pad "3" thru_hole circle
			(at 0.5715 0 180)
			(size 0.508 0.508)
			(drill 0.254)
			(layers "*.Cu" "*.Mask")
			(remove_unused_layers no)
			(net "PHY_SCC_B_TO_DRV_B_35_DN")
			(clearance 0.2286)
			(thermal_gap 0.2286)
		)
		(pad "4" thru_hole circle
			(at 1.5875 0 180)
			(size 0.508 0.508)
			(drill 0.254)
			(layers "*.Cu" "*.Mask")
			(remove_unused_layers no)
			(net "GND")
			(clearance 0.2286)
			(thermal_gap 0.2286)
		)
	)
	(footprint ""
		(layer "F.Cu")
		(at 74.369168 -97.404428 -90)
		(property "Reference" "R374"
			(at 0 0 270)
			(layer "F.SilkS")
			(hide yes)
			(effects
				(font
					(size 1.27 1.27)
				)
			)
		)
		(property "Value" "4K7R2F-GP"
			(at 0.064008 -3.993896 270)
			(unlocked yes)
			(layer "F.Fab")
			(hide yes)
			(effects
				(font
					(size 1.016 1.016)
					(thickness 0.1524)
				)
			)
		)
		(property "Device Type" "R402H16"
			(at 0.064008 -5.517896 270)
			(unlocked yes)
			(layer "F.Fab")
			(hide yes)
			(effects
				(font
					(size 1.016 1.016)
					(thickness 0.1524)
				)
			)
		)
		(duplicate_pad_numbers_are_jumpers no)
		(fp_line
			(start -0.508 -0.9398)
			(end -0.508 0.9398)
			(stroke
				(width 0.1524)
				(type default)
			)
			(layer "F.SilkS")
		)
		(fp_line
			(start 0.508 -0.9398)
			(end -0.508 -0.9398)
			(stroke
				(width 0.1524)
				(type default)
			)
			(layer "F.SilkS")
		)
		(fp_rect
			(start -0.508 0.9398)
			(end 0.508 -0.9398)
			(stroke
				(width 0)
				(type default)
			)
			(fill no)
			(layer "F.CrtYd")
		)
		(fp_rect
			(start -0.508 0.9398)
			(end 0.508 -0.9398)
			(stroke
				(width 0)
				(type default)
			)
			(fill no)
			(layer "F.Fab")
		)
		(pad "1" smd custom
			(at 0 -0.4445 270)
			(size 0.1397 0.1397)
			(layers "F.Cu" "F.Mask" "F.Paste")
			(net "DRIVE_B_14_ACT")
			(options
				(clearance outline)
				(anchor circle)
			)
			(primitives
				(gr_poly
					(pts
						(arc
							(start -0.1778 -0.2794)
							(mid -0.249642 -0.249642)
							(end -0.2794 -0.1778)
						)
						(arc
							(start -0.2794 0.1778)
							(mid -0.249642 0.249642)
							(end -0.1778 0.2794)
						)
						(arc
							(start 0.1778 0.2794)
							(mid 0.249642 0.249642)
							(end 0.2794 0.1778)
						)
						(arc
							(start 0.2794 -0.1778)
							(mid 0.249642 -0.249642)
							(end 0.1778 -0.2794)
						)
					)
					(width 0)
					(fill yes)
				)
			)
		)
		(pad "2" smd custom
			(at 0 0.4445 270)
			(size 0.1397 0.1397)
			(layers "F.Cu" "F.Mask" "F.Paste")
			(net "GND")
			(options
				(clearance outline)
				(anchor circle)
			)
			(primitives
				(gr_poly
					(pts
						(arc
							(start -0.1778 -0.2794)
							(mid -0.249642 -0.249642)
							(end -0.2794 -0.1778)
						)
						(arc
							(start -0.2794 0.1778)
							(mid -0.249642 0.249642)
							(end -0.1778 0.2794)
						)
						(arc
							(start 0.1778 0.2794)
							(mid 0.249642 0.249642)
							(end 0.2794 0.1778)
						)
						(arc
							(start 0.2794 -0.1778)
							(mid 0.249642 -0.249642)
							(end 0.1778 -0.2794)
						)
					)
					(width 0)
					(fill yes)
				)
			)
		)
	)
	(footprint ""
		(layer "F.Cu")
		(at 334.772 -10.16 180)
		(property "Reference" "R771"
			(at 0 0 180)
			(layer "F.SilkS")
			(hide yes)
			(effects
				(font
					(size 1.27 1.27)
				)
			)
		)
		(property "Value" "0R2J-2-GP"
			(at 0.064008 -3.993896 180)
			(unlocked yes)
			(layer "F.Fab")
			(hide yes)
			(effects
				(font
					(size 1.016 1.016)
					(thickness 0.1524)
				)
			)
		)
		(property "Device Type" "R402H16"
			(at 0.064008 -5.517896 180)
			(unlocked yes)
			(layer "F.Fab")
			(hide yes)
			(effects
				(font
					(size 1.016 1.016)
					(thickness 0.1524)
				)
			)
		)
		(duplicate_pad_numbers_are_jumpers no)
		(fp_line
			(start 0.508 -0.9398)
			(end -0.508 -0.9398)
			(stroke
				(width 0.1524)
				(type default)
			)
			(layer "F.SilkS")
		)
		(fp_line
			(start -0.508 -0.9398)
			(end -0.508 0.9398)
			(stroke
				(width 0.1524)
				(type default)
			)
			(layer "F.SilkS")
		)
		(fp_rect
			(start -0.508 0.9398)
			(end 0.508 -0.9398)
			(stroke
				(width 0)
				(type default)
			)
			(fill no)
			(layer "F.CrtYd")
		)
		(fp_rect
			(start -0.508 0.9398)
			(end 0.508 -0.9398)
			(stroke
				(width 0)
				(type default)
			)
			(fill no)
			(layer "F.Fab")
		)
		(pad "1" smd custom
			(at 0 -0.4445 180)
			(size 0.1397 0.1397)
			(layers "F.Cu" "F.Mask" "F.Paste")
			(net "DRIVE_B_30_PWR")
			(options
				(clearance outline)
				(anchor circle)
			)
			(primitives
				(gr_poly
					(pts
						(arc
							(start -0.1778 -0.2794)
							(mid -0.249642 -0.249642)
							(end -0.2794 -0.1778)
						)
						(arc
							(start -0.2794 0.1778)
							(mid -0.249642 0.249642)
							(end -0.1778 0.2794)
						)
						(arc
							(start 0.1778 0.2794)
							(mid 0.249642 0.249642)
							(end 0.2794 0.1778)
						)
						(arc
							(start 0.2794 -0.1778)
							(mid 0.249642 -0.249642)
							(end 0.1778 -0.2794)
						)
					)
					(width 0)
					(fill yes)
				)
			)
		)
		(pad "2" smd custom
			(at 0 0.4445 180)
			(size 0.1397 0.1397)
			(layers "F.Cu" "F.Mask" "F.Paste")
			(net "SW_PWR_R_HDD30")
			(options
				(clearance outline)
				(anchor circle)
			)
			(primitives
				(gr_poly
					(pts
						(arc
							(start -0.1778 -0.2794)
							(mid -0.249642 -0.249642)
							(end -0.2794 -0.1778)
						)
						(arc
							(start -0.2794 0.1778)
							(mid -0.249642 0.249642)
							(end -0.1778 0.2794)
						)
						(arc
							(start 0.1778 0.2794)
							(mid 0.249642 0.249642)
							(end 0.2794 0.1778)
						)
						(arc
							(start 0.2794 -0.1778)
							(mid 0.249642 -0.249642)
							(end 0.1778 -0.2794)
						)
					)
					(width 0)
					(fill yes)
				)
			)
		)
	)
	(footprint ""
		(layer "F.Cu")
		(at 305.685698 -361.427014 180)
		(property "Reference" "R504"
			(at 0 0 180)
			(layer "F.SilkS")
			(hide yes)
			(effects
				(font
					(size 1.27 1.27)
				)
			)
		)
		(property "Value" "10KR2F-2-GP"
			(at 0.064008 -3.993896 180)
			(unlocked yes)
			(layer "F.Fab")
			(hide yes)
			(effects
				(font
					(size 1.016 1.016)
					(thickness 0.1524)
				)
			)
		)
		(property "Device Type" "R402H16"
			(at 0.064008 -5.517896 180)
			(unlocked yes)
			(layer "F.Fab")
			(hide yes)
			(effects
				(font
					(size 1.016 1.016)
					(thickness 0.1524)
				)
			)
		)
		(duplicate_pad_numbers_are_jumpers no)
		(fp_line
			(start 0.508 -0.9398)
			(end -0.508 -0.9398)
			(stroke
				(width 0.1524)
				(type default)
			)
			(layer "F.SilkS")
		)
		(fp_line
			(start -0.508 -0.9398)
			(end -0.508 0.9398)
			(stroke
				(width 0.1524)
				(type default)
			)
			(layer "F.SilkS")
		)
		(fp_rect
			(start -0.508 0.9398)
			(end 0.508 -0.9398)
			(stroke
				(width 0)
				(type default)
			)
			(fill no)
			(layer "F.CrtYd")
		)
		(fp_rect
			(start -0.508 0.9398)
			(end 0.508 -0.9398)
			(stroke
				(width 0)
				(type default)
			)
			(fill no)
			(layer "F.Fab")
		)
		(pad "1" smd custom
			(at 0 -0.4445 180)
			(size 0.1397 0.1397)
			(layers "F.Cu" "F.Mask" "F.Paste")
			(net "P3V3_STBY_B")
			(options
				(clearance outline)
				(anchor circle)
			)
			(primitives
				(gr_poly
					(pts
						(arc
							(start -0.1778 -0.2794)
							(mid -0.249642 -0.249642)
							(end -0.2794 -0.1778)
						)
						(arc
							(start -0.2794 0.1778)
							(mid -0.249642 0.249642)
							(end -0.1778 0.2794)
						)
						(arc
							(start 0.1778 0.2794)
							(mid 0.249642 0.249642)
							(end 0.2794 0.1778)
						)
						(arc
							(start 0.2794 -0.1778)
							(mid 0.249642 -0.249642)
							(end 0.1778 -0.2794)
						)
					)
					(width 0)
					(fill yes)
				)
			)
		)
		(pad "2" smd custom
			(at 0 0.4445 180)
			(size 0.1397 0.1397)
			(layers "F.Cu" "F.Mask" "F.Paste")
			(net "FANTACH_B_OE")
			(options
				(clearance outline)
				(anchor circle)
			)
			(primitives
				(gr_poly
					(pts
						(arc
							(start -0.1778 -0.2794)
							(mid -0.249642 -0.249642)
							(end -0.2794 -0.1778)
						)
						(arc
							(start -0.2794 0.1778)
							(mid -0.249642 0.249642)
							(end -0.1778 0.2794)
						)
						(arc
							(start 0.1778 0.2794)
							(mid 0.249642 0.249642)
							(end 0.2794 0.1778)
						)
						(arc
							(start 0.2794 -0.1778)
							(mid 0.249642 -0.249642)
							(end 0.1778 -0.2794)
						)
					)
					(width 0)
					(fill yes)
				)
			)
		)
	)
	(footprint ""
		(layer "F.Cu")
		(at 40.3352 -8.1534 -90)
		(property "Reference" "R131"
			(at 0 0 270)
			(layer "F.SilkS")
			(hide yes)
			(effects
				(font
					(size 1.27 1.27)
				)
			)
		)
		(property "Value" "4K7R2F-GP"
			(at 0.064008 -3.993896 270)
			(unlocked yes)
			(layer "F.Fab")
			(hide yes)
			(effects
				(font
					(size 1.016 1.016)
					(thickness 0.1524)
				)
			)
		)
		(property "Device Type" "R402H16"
			(at 0.064008 -5.517896 270)
			(unlocked yes)
			(layer "F.Fab")
			(hide yes)
			(effects
				(font
					(size 1.016 1.016)
					(thickness 0.1524)
				)
			)
		)
		(duplicate_pad_numbers_are_jumpers no)
		(fp_line
			(start -0.508 -0.9398)
			(end -0.508 0.9398)
			(stroke
				(width 0.1524)
				(type default)
			)
			(layer "F.SilkS")
		)
		(fp_line
			(start 0.508 -0.9398)
			(end -0.508 -0.9398)
			(stroke
				(width 0.1524)
				(type default)
			)
			(layer "F.SilkS")
		)
		(fp_rect
			(start -0.508 0.9398)
			(end 0.508 -0.9398)
			(stroke
				(width 0)
				(type default)
			)
			(fill no)
			(layer "F.CrtYd")
		)
		(fp_rect
			(start -0.508 0.9398)
			(end 0.508 -0.9398)
			(stroke
				(width 0)
				(type default)
			)
			(fill no)
			(layer "F.Fab")
		)
		(pad "1" smd custom
			(at 0 -0.4445 270)
			(size 0.1397 0.1397)
			(layers "F.Cu" "F.Mask" "F.Paste")
			(net "TEMP1_A0")
			(options
				(clearance outline)
				(anchor circle)
			)
			(primitives
				(gr_poly
					(pts
						(arc
							(start -0.1778 -0.2794)
							(mid -0.249642 -0.249642)
							(end -0.2794 -0.1778)
						)
						(arc
							(start -0.2794 0.1778)
							(mid -0.249642 0.249642)
							(end -0.1778 0.2794)
						)
						(arc
							(start 0.1778 0.2794)
							(mid 0.249642 0.249642)
							(end 0.2794 0.1778)
						)
						(arc
							(start 0.2794 -0.1778)
							(mid 0.249642 -0.249642)
							(end 0.1778 -0.2794)
						)
					)
					(width 0)
					(fill yes)
				)
			)
		)
		(pad "2" smd custom
			(at 0 0.4445 270)
			(size 0.1397 0.1397)
			(layers "F.Cu" "F.Mask" "F.Paste")
			(net "GND")
			(options
				(clearance outline)
				(anchor circle)
			)
			(primitives
				(gr_poly
					(pts
						(arc
							(start -0.1778 -0.2794)
							(mid -0.249642 -0.249642)
							(end -0.2794 -0.1778)
						)
						(arc
							(start -0.2794 0.1778)
							(mid -0.249642 0.249642)
							(end -0.1778 0.2794)
						)
						(arc
							(start 0.1778 0.2794)
							(mid 0.249642 0.249642)
							(end 0.2794 0.1778)
						)
						(arc
							(start 0.2794 -0.1778)
							(mid 0.249642 -0.249642)
							(end 0.1778 -0.2794)
						)
					)
					(width 0)
					(fill yes)
				)
			)
		)
	)
	(footprint ""
		(layer "F.Cu")
		(at 11.351768 -212.390228 -90)
		(property "Reference" "R155"
			(at 0 0 270)
			(layer "F.SilkS")
			(hide yes)
			(effects
				(font
					(size 1.27 1.27)
				)
			)
		)
		(property "Value" "4K7R2F-GP"
			(at 0.064008 -3.993896 270)
			(unlocked yes)
			(layer "F.Fab")
			(hide yes)
			(effects
				(font
					(size 1.016 1.016)
					(thickness 0.1524)
				)
			)
		)
		(property "Device Type" "R402H16"
			(at 0.064008 -5.517896 270)
			(unlocked yes)
			(layer "F.Fab")
			(hide yes)
			(effects
				(font
					(size 1.016 1.016)
					(thickness 0.1524)
				)
			)
		)
		(duplicate_pad_numbers_are_jumpers no)
		(fp_line
			(start -0.508 -0.9398)
			(end -0.508 0.9398)
			(stroke
				(width 0.1524)
				(type default)
			)
			(layer "F.SilkS")
		)
		(fp_line
			(start 0.508 -0.9398)
			(end -0.508 -0.9398)
			(stroke
				(width 0.1524)
				(type default)
			)
			(layer "F.SilkS")
		)
		(fp_rect
			(start -0.508 0.9398)
			(end 0.508 -0.9398)
			(stroke
				(width 0)
				(type default)
			)
			(fill no)
			(layer "F.CrtYd")
		)
		(fp_rect
			(start -0.508 0.9398)
			(end 0.508 -0.9398)
			(stroke
				(width 0)
				(type default)
			)
			(fill no)
			(layer "F.Fab")
		)
		(pad "1" smd custom
			(at 0 -0.4445 270)
			(size 0.1397 0.1397)
			(layers "F.Cu" "F.Mask" "F.Paste")
			(net "DRIVE_B_0_ACT")
			(options
				(clearance outline)
				(anchor circle)
			)
			(primitives
				(gr_poly
					(pts
						(arc
							(start -0.1778 -0.2794)
							(mid -0.249642 -0.249642)
							(end -0.2794 -0.1778)
						)
						(arc
							(start -0.2794 0.1778)
							(mid -0.249642 0.249642)
							(end -0.1778 0.2794)
						)
						(arc
							(start 0.1778 0.2794)
							(mid 0.249642 0.249642)
							(end 0.2794 0.1778)
						)
						(arc
							(start 0.2794 -0.1778)
							(mid 0.249642 -0.249642)
							(end 0.1778 -0.2794)
						)
					)
					(width 0)
					(fill yes)
				)
			)
		)
		(pad "2" smd custom
			(at 0 0.4445 270)
			(size 0.1397 0.1397)
			(layers "F.Cu" "F.Mask" "F.Paste")
			(net "GND")
			(options
				(clearance outline)
				(anchor circle)
			)
			(primitives
				(gr_poly
					(pts
						(arc
							(start -0.1778 -0.2794)
							(mid -0.249642 -0.249642)
							(end -0.2794 -0.1778)
						)
						(arc
							(start -0.2794 0.1778)
							(mid -0.249642 0.249642)
							(end -0.1778 0.2794)
						)
						(arc
							(start 0.1778 0.2794)
							(mid 0.249642 0.249642)
							(end 0.2794 0.1778)
						)
						(arc
							(start 0.2794 -0.1778)
							(mid 0.249642 -0.249642)
							(end 0.1778 -0.2794)
						)
					)
					(width 0)
					(fill yes)
				)
			)
		)
	)
	(footprint ""
		(layer "F.Cu")
		(at 239.870742 -141.3764 90)
		(property "Reference" "R440"
			(at 0 0 90)
			(layer "F.SilkS")
			(hide yes)
			(effects
				(font
					(size 1.27 1.27)
				)
			)
		)
		(property "Value" "10KR2F-2-GP"
			(at 0.064008 -3.993896 90)
			(unlocked yes)
			(layer "F.Fab")
			(hide yes)
			(effects
				(font
					(size 1.016 1.016)
					(thickness 0.1524)
				)
			)
		)
		(property "Device Type" "R402H16"
			(at 0.064008 -5.517896 90)
			(unlocked yes)
			(layer "F.Fab")
			(hide yes)
			(effects
				(font
					(size 1.016 1.016)
					(thickness 0.1524)
				)
			)
		)
		(duplicate_pad_numbers_are_jumpers no)
		(fp_line
			(start 0.508 -0.9398)
			(end -0.508 -0.9398)
			(stroke
				(width 0.1524)
				(type default)
			)
			(layer "F.SilkS")
		)
		(fp_line
			(start -0.508 -0.9398)
			(end -0.508 0.9398)
			(stroke
				(width 0.1524)
				(type default)
			)
			(layer "F.SilkS")
		)
		(fp_rect
			(start -0.508 0.9398)
			(end 0.508 -0.9398)
			(stroke
				(width 0)
				(type default)
			)
			(fill no)
			(layer "F.CrtYd")
		)
		(fp_rect
			(start -0.508 0.9398)
			(end 0.508 -0.9398)
			(stroke
				(width 0)
				(type default)
			)
			(fill no)
			(layer "F.Fab")
		)
		(pad "1" smd custom
			(at 0 -0.4445 90)
			(size 0.1397 0.1397)
			(layers "F.Cu" "F.Mask" "F.Paste")
			(net "P3V3_STBY_B")
			(options
				(clearance outline)
				(anchor circle)
			)
			(primitives
				(gr_poly
					(pts
						(arc
							(start -0.1778 -0.2794)
							(mid -0.249642 -0.249642)
							(end -0.2794 -0.1778)
						)
						(arc
							(start -0.2794 0.1778)
							(mid -0.249642 0.249642)
							(end -0.1778 0.2794)
						)
						(arc
							(start 0.1778 0.2794)
							(mid 0.249642 0.249642)
							(end 0.2794 0.1778)
						)
						(arc
							(start 0.2794 -0.1778)
							(mid 0.249642 -0.249642)
							(end 0.1778 -0.2794)
						)
					)
					(width 0)
					(fill yes)
				)
			)
		)
		(pad "2" smd custom
			(at 0 0.4445 90)
			(size 0.1397 0.1397)
			(layers "F.Cu" "F.Mask" "F.Paste")
			(net "I2C_SCC_BUFF_EN")
			(options
				(clearance outline)
				(anchor circle)
			)
			(primitives
				(gr_poly
					(pts
						(arc
							(start -0.1778 -0.2794)
							(mid -0.249642 -0.249642)
							(end -0.2794 -0.1778)
						)
						(arc
							(start -0.2794 0.1778)
							(mid -0.249642 0.249642)
							(end -0.1778 0.2794)
						)
						(arc
							(start 0.1778 0.2794)
							(mid 0.249642 0.249642)
							(end 0.2794 0.1778)
						)
						(arc
							(start 0.2794 -0.1778)
							(mid 0.249642 -0.249642)
							(end 0.1778 -0.2794)
						)
					)
					(width 0)
					(fill yes)
				)
			)
		)
	)
)
